# S9S_MB_2U (Grand Teton) — schematic netlist excerpt (pin names and nets, part order shuffled) for the footprints in the layout excerpt that follows; sources: Cadence DE-HDL packaged netlist, KiCad conversion of 03242023_DA0F0TMBIJ0_F0T_Motherboard_J_brd_V01_OCP.brd

R3112  Q_RES  33.2 1% CHIP  pkg 0402LF  page 234 : A = I3C_BMC_SWB_SCL ; B = I3C_BMC_SWB_R_SCL
R742  Q_RES  75 1% CHIP  pkg 0402LF  page 133 : A = PVNN_TERM_CPU1 ; B = JTAG_CPU1_MUX_GTL_TDO

(kicad_pcb
	(version 20260206)
	(generator "pcbnew")
	(generator_version "10.0")
	(general
		(thickness 1.6)
		(legacy_teardrops no)
	)
	(paper "A4")
	(title_block
		(title "03242023_DA0F0TMBIJ0_F0T_Motherboard_J_brd_V01_OCP.brd")
		(comment 1 "Grand Teton / footprints 5547-5548 of 6105")
	)
	(layers
		(0 "F.Cu" signal "TOP")
		(4 "In1.Cu" signal "GND")
		(6 "In2.Cu" signal "IN1")
		(8 "In3.Cu" signal "GND1")
		(10 "In4.Cu" signal "IN2")
		(12 "In5.Cu" signal "GND2")
		(14 "In6.Cu" signal "IN3")
		(16 "In7.Cu" signal "GND3")
		(18 "In8.Cu" signal "VCC")
		(20 "In9.Cu" signal "VCC1")
		(22 "In10.Cu" signal "GND4")
		(24 "In11.Cu" signal "IN4")
		(26 "In12.Cu" signal "GND5")
		(28 "In13.Cu" signal "IN5")
		(30 "In14.Cu" signal "GND6")
		(32 "In15.Cu" signal "IN6")
		(34 "In16.Cu" signal "GND7")
		(2 "B.Cu" signal "BOTTOM")
		(9 "F.Adhes" user "F.Adhesive")
		(11 "B.Adhes" user "B.Adhesive")
		(13 "F.Paste" user "Package Geometry/Pastemask Top")
		(15 "B.Paste" user "Package Geometry/Pastemask Bottom")
		(5 "F.SilkS" user "Ref Des/Silkscreen Top")
		(7 "B.SilkS" user "Ref Des/Silkscreen Bottom")
		(1 "F.Mask" user "Board Geometry/Soldermask Top")
		(3 "B.Mask" user "Board Geometry/Soldermask Bottom")
		(17 "Dwgs.User" user "User.Drawings")
		(19 "Cmts.User" user "User.Comments")
		(21 "Eco1.User" user "User.Eco1")
		(23 "Eco2.User" user "User.Eco2")
		(25 "Edge.Cuts" user "Board Geometry/Outline")
		(27 "Margin" user)
		(31 "F.CrtYd" user "Package Geometry/Place Bound Top")
		(29 "B.CrtYd" user "Package Geometry/Place Bound Bottom")
		(35 "F.Fab" user "Ref Des/Assembly Top")
		(33 "B.Fab" user "Ref Des/Assembly Bottom")
	)
	(footprint ""
		(layer "B.Cu")
		(at 174.163228 -8.904478 180)
		(property "Reference" "R3112"
			(at 0 0 0)
			(layer "B.SilkS")
			(hide yes)
			(effects
				(font
					(size 1.27 1.27)
				)
				(justify mirror)
			)
		)
		(property "Value" ""
			(at 0 0 0)
			(layer "B.Fab")
			(effects
				(font
					(size 1.27 1.27)
				)
				(justify mirror)
			)
		)
		(duplicate_pad_numbers_are_jumpers no)
		(fp_line
			(start 0.7874 0.4064)
			(end 0.7874 -0.4064)
			(stroke
				(width 0.1524)
				(type default)
			)
			(layer "B.SilkS")
		)
		(fp_line
			(start 0.7874 -0.4064)
			(end -0.7874 -0.4064)
			(stroke
				(width 0.1524)
				(type default)
			)
			(layer "B.SilkS")
		)
		(fp_line
			(start -0.7874 0.4064)
			(end 0.7874 0.4064)
			(stroke
				(width 0.1524)
				(type default)
			)
			(layer "B.SilkS")
		)
		(fp_line
			(start -0.7874 -0.4064)
			(end -0.7874 0.4064)
			(stroke
				(width 0.1524)
				(type default)
			)
			(layer "B.SilkS")
		)
		(fp_line
			(start 0.67945 0.3048)
			(end 0.67945 -0.305054)
			(stroke
				(width 0.1)
				(type default)
			)
			(layer "B.Fab")
		)
		(fp_line
			(start 0.67945 -0.305054)
			(end 0.12065 -0.305054)
			(stroke
				(width 0.1)
				(type default)
			)
			(layer "B.Fab")
		)
		(fp_line
			(start 0.12065 0.3048)
			(end 0.67945 0.3048)
			(stroke
				(width 0.1)
				(type default)
			)
			(layer "B.Fab")
		)
		(fp_line
			(start 0.12065 0.2794)
			(end 0.12065 0.3048)
			(stroke
				(width 0.1)
				(type default)
			)
			(layer "B.Fab")
		)
		(fp_line
			(start 0.12065 -0.2794)
			(end -0.12065 -0.2794)
			(stroke
				(width 0.1)
				(type default)
			)
			(layer "B.Fab")
		)
		(fp_line
			(start 0.12065 -0.305054)
			(end 0.12065 -0.2794)
			(stroke
				(width 0.1)
				(type default)
			)
			(layer "B.Fab")
		)
		(fp_line
			(start -0.120396 0.3048)
			(end -0.120396 0.2794)
			(stroke
				(width 0.1)
				(type default)
			)
			(layer "B.Fab")
		)
		(fp_line
			(start -0.120396 0.2794)
			(end 0.12065 0.2794)
			(stroke
				(width 0.1)
				(type default)
			)
			(layer "B.Fab")
		)
		(fp_line
			(start -0.12065 -0.2794)
			(end -0.12065 -0.3048)
			(stroke
				(width 0.1)
				(type default)
			)
			(layer "B.Fab")
		)
		(fp_line
			(start -0.12065 -0.3048)
			(end -0.67945 -0.3048)
			(stroke
				(width 0.1)
				(type default)
			)
			(layer "B.Fab")
		)
		(fp_line
			(start -0.67945 0.3048)
			(end -0.120396 0.3048)
			(stroke
				(width 0.1)
				(type default)
			)
			(layer "B.Fab")
		)
		(fp_line
			(start -0.67945 -0.3048)
			(end -0.67945 0.3048)
			(stroke
				(width 0.1)
				(type default)
			)
			(layer "B.Fab")
		)
		(pad "1" smd circle
			(at 0.40005 0)
			(size 0 0)
			(layers "B.Cu" "B.Mask" "B.Paste")
			(net "I3C_BMC_SWB_SCL")
		)
		(pad "2" smd circle
			(at -0.40005 0)
			(size 0 0)
			(layers "B.Cu" "B.Mask" "B.Paste")
			(net "I3C_BMC_SWB_R_SCL")
		)
	)
	(footprint ""
		(layer "B.Cu")
		(at 91.161108 -190.705232 -90)
		(property "Reference" "R742"
			(at 0 0 90)
			(layer "B.SilkS")
			(hide yes)
			(effects
				(font
					(size 1.27 1.27)
				)
				(justify mirror)
			)
		)
		(property "Value" ""
			(at 0 0 90)
			(layer "B.Fab")
			(effects
				(font
					(size 1.27 1.27)
				)
				(justify mirror)
			)
		)
		(duplicate_pad_numbers_are_jumpers no)
		(fp_line
			(start -0.7874 0.4064)
			(end 0.7874 0.4064)
			(stroke
				(width 0.1524)
				(type default)
			)
			(layer "B.SilkS")
		)
		(fp_line
			(start 0.7874 0.4064)
			(end 0.7874 -0.4064)
			(stroke
				(width 0.1524)
				(type default)
			)
			(layer "B.SilkS")
		)
		(fp_line
			(start -0.7874 -0.4064)
			(end -0.7874 0.4064)
			(stroke
				(width 0.1524)
				(type default)
			)
			(layer "B.SilkS")
		)
		(fp_line
			(start 0.7874 -0.4064)
			(end -0.7874 -0.4064)
			(stroke
				(width 0.1524)
				(type default)
			)
			(layer "B.SilkS")
		)
		(fp_line
			(start -0.67945 0.3048)
			(end -0.120396 0.3048)
			(stroke
				(width 0.1)
				(type default)
			)
			(layer "B.Fab")
		)
		(fp_line
			(start -0.120396 0.3048)
			(end -0.120396 0.2794)
			(stroke
				(width 0.1)
				(type default)
			)
			(layer "B.Fab")
		)
		(fp_line
			(start 0.12065 0.3048)
			(end 0.67945 0.3048)
			(stroke
				(width 0.1)
				(type default)
			)
			(layer "B.Fab")
		)
		(fp_line
			(start 0.67945 0.3048)
			(end 0.67945 -0.305054)
			(stroke
				(width 0.1)
				(type default)
			)
			(layer "B.Fab")
		)
		(fp_line
			(start -0.120396 0.2794)
			(end 0.12065 0.2794)
			(stroke
				(width 0.1)
				(type default)
			)
			(layer "B.Fab")
		)
		(fp_line
			(start 0.12065 0.2794)
			(end 0.12065 0.3048)
			(stroke
				(width 0.1)
				(type default)
			)
			(layer "B.Fab")
		)
		(fp_line
			(start -0.12065 -0.2794)
			(end -0.12065 -0.3048)
			(stroke
				(width 0.1)
				(type default)
			)
			(layer "B.Fab")
		)
		(fp_line
			(start 0.12065 -0.2794)
			(end -0.12065 -0.2794)
			(stroke
				(width 0.1)
				(type default)
			)
			(layer "B.Fab")
		)
		(fp_line
			(start -0.67945 -0.3048)
			(end -0.67945 0.3048)
			(stroke
				(width 0.1)
				(type default)
			)
			(layer "B.Fab")
		)
		(fp_line
			(start -0.12065 -0.3048)
			(end -0.67945 -0.3048)
			(stroke
				(width 0.1)
				(type default)
			)
			(layer "B.Fab")
		)
		(fp_line
			(start 0.12065 -0.305054)
			(end 0.12065 -0.2794)
			(stroke
				(width 0.1)
				(type default)
			)
			(layer "B.Fab")
		)
		(fp_line
			(start 0.67945 -0.305054)
			(end 0.12065 -0.305054)
			(stroke
				(width 0.1)
				(type default)
			)
			(layer "B.Fab")
		)
		(pad "1" smd circle
			(at 0.40005 0 90)
			(size 0 0)
			(layers "B.Cu" "B.Mask" "B.Paste")
			(net "PVNN_TERM_CPU1")
		)
		(pad "2" smd circle
			(at -0.40005 0 90)
			(size 0 0)
			(layers "B.Cu" "B.Mask" "B.Paste")
			(net "JTAG_CPU1_MUX_GTL_TDO")
		)
	)
)
